(kicad_pcb
	(version 20260206)
	(generator "pcbnew")
	(generator_version "10.0")
	(general
		(thickness 1.6)
		(legacy_teardrops no)
	)
	(paper "A4")
	(title_block
		(title "03242023_DA0F0TMBIJ0_F0T_Motherboard_J_brd_V01_OCP.brd")
		(comment 1 "Grand Teton / footprints 1210-1214 of 6105")
	)
	(layers
		(0 "F.Cu" signal "TOP")
		(4 "In1.Cu" signal "GND")
		(6 "In2.Cu" signal "IN1")
		(8 "In3.Cu" signal "GND1")
		(10 "In4.Cu" signal "IN2")
		(12 "In5.Cu" signal "GND2")
		(14 "In6.Cu" signal "IN3")
		(16 "In7.Cu" signal "GND3")
		(18 "In8.Cu" signal "VCC")
		(20 "In9.Cu" signal "VCC1")
		(22 "In10.Cu" signal "GND4")
		(24 "In11.Cu" signal "IN4")
		(26 "In12.Cu" signal "GND5")
		(28 "In13.Cu" signal "IN5")
		(30 "In14.Cu" signal "GND6")
		(32 "In15.Cu" signal "IN6")
		(34 "In16.Cu" signal "GND7")
		(2 "B.Cu" signal "BOTTOM")
		(9 "F.Adhes" user "F.Adhesive")
		(11 "B.Adhes" user "B.Adhesive")
		(13 "F.Paste" user "Package Geometry/Pastemask Top")
		(15 "B.Paste" user "Package Geometry/Pastemask Bottom")
		(5 "F.SilkS" user "Ref Des/Silkscreen Top")
		(7 "B.SilkS" user "Ref Des/Silkscreen Bottom")
		(1 "F.Mask" user "Board Geometry/Soldermask Top")
		(3 "B.Mask" user "Board Geometry/Soldermask Bottom")
		(17 "Dwgs.User" user "User.Drawings")
		(19 "Cmts.User" user "User.Comments")
		(21 "Eco1.User" user "User.Eco1")
		(23 "Eco2.User" user "User.Eco2")
		(25 "Edge.Cuts" user "Board Geometry/Outline")
		(27 "Margin" user)
		(31 "F.CrtYd" user "Package Geometry/Place Bound Top")
		(29 "B.CrtYd" user "Package Geometry/Place Bound Bottom")
		(35 "F.Fab" user "Ref Des/Assembly Top")
		(33 "B.Fab" user "Ref Des/Assembly Bottom")
	)
	(footprint ""
		(layer "F.Cu")
		(at 119.508016 -256.6543 -90)
		(property "Reference" "C253"
			(at 0 0 270)
			(layer "F.SilkS")
			(hide yes)
			(effects
				(font
					(size 1.27 1.27)
				)
			)
		)
		(property "Value" ""
			(at 0 0 270)
			(layer "F.Fab")
			(effects
				(font
					(size 1.27 1.27)
				)
			)
		)
		(duplicate_pad_numbers_are_jumpers no)
		(fp_line
			(start -0.7874 0.4064)
			(end -0.7874 -0.4064)
			(stroke
				(width 0.1524)
				(type default)
			)
			(layer "F.SilkS")
		)
		(fp_line
			(start 0.7874 0.4064)
			(end -0.7874 0.4064)
			(stroke
				(width 0.1524)
				(type default)
			)
			(layer "F.SilkS")
		)
		(fp_line
			(start -0.7874 -0.4064)
			(end 0.7874 -0.4064)
			(stroke
				(width 0.1524)
				(type default)
			)
			(layer "F.SilkS")
		)
		(fp_line
			(start 0.7874 -0.4064)
			(end 0.7874 0.4064)
			(stroke
				(width 0.1524)
				(type default)
			)
			(layer "F.SilkS")
		)
		(fp_line
			(start -0.67945 0.3048)
			(end -0.67945 -0.305054)
			(stroke
				(width 0.1)
				(type default)
			)
			(layer "F.Fab")
		)
		(fp_line
			(start -0.12065 0.3048)
			(end -0.67945 0.3048)
			(stroke
				(width 0.1)
				(type default)
			)
			(layer "F.Fab")
		)
		(fp_line
			(start 0.120396 0.3048)
			(end 0.120396 0.2794)
			(stroke
				(width 0.1)
				(type default)
			)
			(layer "F.Fab")
		)
		(fp_line
			(start 0.67945 0.3048)
			(end 0.120396 0.3048)
			(stroke
				(width 0.1)
				(type default)
			)
			(layer "F.Fab")
		)
		(fp_line
			(start -0.12065 0.2794)
			(end -0.12065 0.3048)
			(stroke
				(width 0.1)
				(type default)
			)
			(layer "F.Fab")
		)
		(fp_line
			(start 0.120396 0.2794)
			(end -0.12065 0.2794)
			(stroke
				(width 0.1)
				(type default)
			)
			(layer "F.Fab")
		)
		(fp_line
			(start -0.12065 -0.2794)
			(end 0.12065 -0.2794)
			(stroke
				(width 0.1)
				(type default)
			)
			(layer "F.Fab")
		)
		(fp_line
			(start 0.12065 -0.2794)
			(end 0.12065 -0.3048)
			(stroke
				(width 0.1)
				(type default)
			)
			(layer "F.Fab")
		)
		(fp_line
			(start 0.12065 -0.3048)
			(end 0.67945 -0.3048)
			(stroke
				(width 0.1)
				(type default)
			)
			(layer "F.Fab")
		)
		(fp_line
			(start 0.67945 -0.3048)
			(end 0.67945 0.3048)
			(stroke
				(width 0.1)
				(type default)
			)
			(layer "F.Fab")
		)
		(fp_line
			(start -0.67945 -0.305054)
			(end -0.12065 -0.305054)
			(stroke
				(width 0.1)
				(type default)
			)
			(layer "F.Fab")
		)
		(fp_line
			(start -0.12065 -0.305054)
			(end -0.12065 -0.2794)
			(stroke
				(width 0.1)
				(type default)
			)
			(layer "F.Fab")
		)
		(pad "1" smd circle
			(at -0.40005 0 270)
			(size 0 0)
			(layers "F.Cu" "F.Mask" "F.Paste")
			(net "PVCCIN_CPU1")
		)
		(pad "2" smd circle
			(at 0.40005 0 270)
			(size 0 0)
			(layers "F.Cu" "F.Mask" "F.Paste")
			(net "GND")
		)
	)
	(footprint ""
		(layer "F.Cu")
		(at 162.34283 -80.159098)
		(property "Reference" "R2211"
			(at 0 0 0)
			(layer "F.SilkS")
			(hide yes)
			(effects
				(font
					(size 1.27 1.27)
				)
			)
		)
		(property "Value" ""
			(at 0 0 0)
			(layer "F.Fab")
			(effects
				(font
					(size 1.27 1.27)
				)
			)
		)
		(duplicate_pad_numbers_are_jumpers no)
		(fp_line
			(start -0.7874 -0.4064)
			(end 0.7874 -0.4064)
			(stroke
				(width 0.1524)
				(type default)
			)
			(layer "F.SilkS")
		)
		(fp_line
			(start -0.7874 0.4064)
			(end -0.7874 -0.4064)
			(stroke
				(width 0.1524)
				(type default)
			)
			(layer "F.SilkS")
		)
		(fp_line
			(start 0.7874 -0.4064)
			(end 0.7874 0.4064)
			(stroke
				(width 0.1524)
				(type default)
			)
			(layer "F.SilkS")
		)
		(fp_line
			(start 0.7874 0.4064)
			(end -0.7874 0.4064)
			(stroke
				(width 0.1524)
				(type default)
			)
			(layer "F.SilkS")
		)
		(fp_line
			(start -0.67945 -0.305054)
			(end -0.12065 -0.305054)
			(stroke
				(width 0.1)
				(type default)
			)
			(layer "F.Fab")
		)
		(fp_line
			(start -0.67945 0.3048)
			(end -0.67945 -0.305054)
			(stroke
				(width 0.1)
				(type default)
			)
			(layer "F.Fab")
		)
		(fp_line
			(start -0.12065 -0.305054)
			(end -0.12065 -0.2794)
			(stroke
				(width 0.1)
				(type default)
			)
			(layer "F.Fab")
		)
		(fp_line
			(start -0.12065 -0.2794)
			(end 0.12065 -0.2794)
			(stroke
				(width 0.1)
				(type default)
			)
			(layer "F.Fab")
		)
		(fp_line
			(start -0.12065 0.2794)
			(end -0.12065 0.3048)
			(stroke
				(width 0.1)
				(type default)
			)
			(layer "F.Fab")
		)
		(fp_line
			(start -0.12065 0.3048)
			(end -0.67945 0.3048)
			(stroke
				(width 0.1)
				(type default)
			)
			(layer "F.Fab")
		)
		(fp_line
			(start 0.120396 0.2794)
			(end -0.12065 0.2794)
			(stroke
				(width 0.1)
				(type default)
			)
			(layer "F.Fab")
		)
		(fp_line
			(start 0.120396 0.3048)
			(end 0.120396 0.2794)
			(stroke
				(width 0.1)
				(type default)
			)
			(layer "F.Fab")
		)
		(fp_line
			(start 0.12065 -0.3048)
			(end 0.67945 -0.3048)
			(stroke
				(width 0.1)
				(type default)
			)
			(layer "F.Fab")
		)
		(fp_line
			(start 0.12065 -0.2794)
			(end 0.12065 -0.3048)
			(stroke
				(width 0.1)
				(type default)
			)
			(layer "F.Fab")
		)
		(fp_line
			(start 0.67945 -0.3048)
			(end 0.67945 0.3048)
			(stroke
				(width 0.1)
				(type default)
			)
			(layer "F.Fab")
		)
		(fp_line
			(start 0.67945 0.3048)
			(end 0.120396 0.3048)
			(stroke
				(width 0.1)
				(type default)
			)
			(layer "F.Fab")
		)
		(pad "1" smd circle
			(at -0.40005 0)
			(size 0 0)
			(layers "F.Cu" "F.Mask" "F.Paste")
			(net "SMB_S3M_CPU1_3V3AUX_SCL_R")
		)
		(pad "2" smd circle
			(at 0.40005 0)
			(size 0 0)
			(layers "F.Cu" "F.Mask" "F.Paste")
			(net "SMB_S3M_CPU1_3V3AUX_SCL")
		)
	)
	(footprint ""
		(layer "F.Cu")
		(at 257.85953 -55.479442)
		(property "Reference" "R3956"
			(at 0 0 0)
			(layer "F.SilkS")
			(hide yes)
			(effects
				(font
					(size 1.27 1.27)
				)
			)
		)
		(property "Value" ""
			(at 0 0 0)
			(layer "F.Fab")
			(effects
				(font
					(size 1.27 1.27)
				)
			)
		)
		(duplicate_pad_numbers_are_jumpers no)
		(fp_line
			(start -0.7874 -0.4064)
			(end 0.7874 -0.4064)
			(stroke
				(width 0.1524)
				(type default)
			)
			(layer "F.SilkS")
		)
		(fp_line
			(start -0.7874 0.4064)
			(end -0.7874 -0.4064)
			(stroke
				(width 0.1524)
				(type default)
			)
			(layer "F.SilkS")
		)
		(fp_line
			(start 0.7874 -0.4064)
			(end 0.7874 0.4064)
			(stroke
				(width 0.1524)
				(type default)
			)
			(layer "F.SilkS")
		)
		(fp_line
			(start 0.7874 0.4064)
			(end -0.7874 0.4064)
			(stroke
				(width 0.1524)
				(type default)
			)
			(layer "F.SilkS")
		)
		(fp_line
			(start -0.67945 -0.305054)
			(end -0.12065 -0.305054)
			(stroke
				(width 0.1)
				(type default)
			)
			(layer "F.Fab")
		)
		(fp_line
			(start -0.67945 0.3048)
			(end -0.67945 -0.305054)
			(stroke
				(width 0.1)
				(type default)
			)
			(layer "F.Fab")
		)
		(fp_line
			(start -0.12065 -0.305054)
			(end -0.12065 -0.2794)
			(stroke
				(width 0.1)
				(type default)
			)
			(layer "F.Fab")
		)
		(fp_line
			(start -0.12065 -0.2794)
			(end 0.12065 -0.2794)
			(stroke
				(width 0.1)
				(type default)
			)
			(layer "F.Fab")
		)
		(fp_line
			(start -0.12065 0.2794)
			(end -0.12065 0.3048)
			(stroke
				(width 0.1)
				(type default)
			)
			(layer "F.Fab")
		)
		(fp_line
			(start -0.12065 0.3048)
			(end -0.67945 0.3048)
			(stroke
				(width 0.1)
				(type default)
			)
			(layer "F.Fab")
		)
		(fp_line
			(start 0.120396 0.2794)
			(end -0.12065 0.2794)
			(stroke
				(width 0.1)
				(type default)
			)
			(layer "F.Fab")
		)
		(fp_line
			(start 0.120396 0.3048)
			(end 0.120396 0.2794)
			(stroke
				(width 0.1)
				(type default)
			)
			(layer "F.Fab")
		)
		(fp_line
			(start 0.12065 -0.3048)
			(end 0.67945 -0.3048)
			(stroke
				(width 0.1)
				(type default)
			)
			(layer "F.Fab")
		)
		(fp_line
			(start 0.12065 -0.2794)
			(end 0.12065 -0.3048)
			(stroke
				(width 0.1)
				(type default)
			)
			(layer "F.Fab")
		)
		(fp_line
			(start 0.67945 -0.3048)
			(end 0.67945 0.3048)
			(stroke
				(width 0.1)
				(type default)
			)
			(layer "F.Fab")
		)
		(fp_line
			(start 0.67945 0.3048)
			(end 0.120396 0.3048)
			(stroke
				(width 0.1)
				(type default)
			)
			(layer "F.Fab")
		)
		(pad "1" smd circle
			(at -0.40005 0)
			(size 0 0)
			(layers "F.Cu" "F.Mask" "F.Paste")
			(net "P12V_E1S_IMON_0")
		)
		(pad "2" smd circle
			(at 0.40005 0)
			(size 0 0)
			(layers "F.Cu" "F.Mask" "F.Paste")
			(net "P12V_E1S_0_ISENSE_MPS_TIC")
		)
	)
	(footprint ""
		(layer "F.Cu")
		(at 162.34283 -73.727818 180)
		(property "Reference" "R2313"
			(at 0 0 180)
			(layer "F.SilkS")
			(hide yes)
			(effects
				(font
					(size 1.27 1.27)
				)
			)
		)
		(property "Value" ""
			(at 0 0 180)
			(layer "F.Fab")
			(effects
				(font
					(size 1.27 1.27)
				)
			)
		)
		(duplicate_pad_numbers_are_jumpers no)
		(fp_line
			(start 0.7874 0.4064)
			(end -0.7874 0.4064)
			(stroke
				(width 0.1524)
				(type default)
			)
			(layer "F.SilkS")
		)
		(fp_line
			(start 0.7874 -0.4064)
			(end 0.7874 0.4064)
			(stroke
				(width 0.1524)
				(type default)
			)
			(layer "F.SilkS")
		)
		(fp_line
			(start -0.7874 0.4064)
			(end -0.7874 -0.4064)
			(stroke
				(width 0.1524)
				(type default)
			)
			(layer "F.SilkS")
		)
		(fp_line
			(start -0.7874 -0.4064)
			(end 0.7874 -0.4064)
			(stroke
				(width 0.1524)
				(type default)
			)
			(layer "F.SilkS")
		)
		(fp_line
			(start 0.67945 0.3048)
			(end 0.120396 0.3048)
			(stroke
				(width 0.1)
				(type default)
			)
			(layer "F.Fab")
		)
		(fp_line
			(start 0.67945 -0.3048)
			(end 0.67945 0.3048)
			(stroke
				(width 0.1)
				(type default)
			)
			(layer "F.Fab")
		)
		(fp_line
			(start 0.12065 -0.2794)
			(end 0.12065 -0.3048)
			(stroke
				(width 0.1)
				(type default)
			)
			(layer "F.Fab")
		)
		(fp_line
			(start 0.12065 -0.3048)
			(end 0.67945 -0.3048)
			(stroke
				(width 0.1)
				(type default)
			)
			(layer "F.Fab")
		)
		(fp_line
			(start 0.120396 0.3048)
			(end 0.120396 0.2794)
			(stroke
				(width 0.1)
				(type default)
			)
			(layer "F.Fab")
		)
		(fp_line
			(start 0.120396 0.2794)
			(end -0.12065 0.2794)
			(stroke
				(width 0.1)
				(type default)
			)
			(layer "F.Fab")
		)
		(fp_line
			(start -0.12065 0.3048)
			(end -0.67945 0.3048)
			(stroke
				(width 0.1)
				(type default)
			)
			(layer "F.Fab")
		)
		(fp_line
			(start -0.12065 0.2794)
			(end -0.12065 0.3048)
			(stroke
				(width 0.1)
				(type default)
			)
			(layer "F.Fab")
		)
		(fp_line
			(start -0.12065 -0.2794)
			(end 0.12065 -0.2794)
			(stroke
				(width 0.1)
				(type default)
			)
			(layer "F.Fab")
		)
		(fp_line
			(start -0.12065 -0.305054)
			(end -0.12065 -0.2794)
			(stroke
				(width 0.1)
				(type default)
			)
			(layer "F.Fab")
		)
		(fp_line
			(start -0.67945 0.3048)
			(end -0.67945 -0.305054)
			(stroke
				(width 0.1)
				(type default)
			)
			(layer "F.Fab")
		)
		(fp_line
			(start -0.67945 -0.305054)
			(end -0.12065 -0.305054)
			(stroke
				(width 0.1)
				(type default)
			)
			(layer "F.Fab")
		)
		(pad "1" smd circle
			(at -0.40005 0 180)
			(size 0 0)
			(layers "F.Cu" "F.Mask" "F.Paste")
			(net "RST_SMB_SWITCH_N")
		)
		(pad "2" smd circle
			(at 0.40005 0 180)
			(size 0 0)
			(layers "F.Cu" "F.Mask" "F.Paste")
			(net "RST_SMB_S3M_N")
		)
	)
	(footprint ""
		(layer "F.Cu")
		(at 128.401572 -133.050026)
		(property "Reference" "R3581"
			(at 0 0 0)
			(layer "F.SilkS")
			(hide yes)
			(effects
				(font
					(size 1.27 1.27)
				)
			)
		)
		(property "Value" ""
			(at 0 0 0)
			(layer "F.Fab")
			(effects
				(font
					(size 1.27 1.27)
				)
			)
		)
		(duplicate_pad_numbers_are_jumpers no)
		(fp_line
			(start -0.7874 -0.4064)
			(end 0.7874 -0.4064)
			(stroke
				(width 0.1524)
				(type default)
			)
			(layer "F.SilkS")
		)
		(fp_line
			(start -0.7874 0.4064)
			(end -0.7874 -0.4064)
			(stroke
				(width 0.1524)
				(type default)
			)
			(layer "F.SilkS")
		)
		(fp_line
			(start 0.7874 -0.4064)
			(end 0.7874 0.4064)
			(stroke
				(width 0.1524)
				(type default)
			)
			(layer "F.SilkS")
		)
		(fp_line
			(start 0.7874 0.4064)
			(end -0.7874 0.4064)
			(stroke
				(width 0.1524)
				(type default)
			)
			(layer "F.SilkS")
		)
		(fp_line
			(start -0.67945 -0.305054)
			(end -0.12065 -0.305054)
			(stroke
				(width 0.1)
				(type default)
			)
			(layer "F.Fab")
		)
		(fp_line
			(start -0.67945 0.3048)
			(end -0.67945 -0.305054)
			(stroke
				(width 0.1)
				(type default)
			)
			(layer "F.Fab")
		)
		(fp_line
			(start -0.12065 -0.305054)
			(end -0.12065 -0.2794)
			(stroke
				(width 0.1)
				(type default)
			)
			(layer "F.Fab")
		)
		(fp_line
			(start -0.12065 -0.2794)
			(end 0.12065 -0.2794)
			(stroke
				(width 0.1)
				(type default)
			)
			(layer "F.Fab")
		)
		(fp_line
			(start -0.12065 0.2794)
			(end -0.12065 0.3048)
			(stroke
				(width 0.1)
				(type default)
			)
			(layer "F.Fab")
		)
		(fp_line
			(start -0.12065 0.3048)
			(end -0.67945 0.3048)
			(stroke
				(width 0.1)
				(type default)
			)
			(layer "F.Fab")
		)
		(fp_line
			(start 0.120396 0.2794)
			(end -0.12065 0.2794)
			(stroke
				(width 0.1)
				(type default)
			)
			(layer "F.Fab")
		)
		(fp_line
			(start 0.120396 0.3048)
			(end 0.120396 0.2794)
			(stroke
				(width 0.1)
				(type default)
			)
			(layer "F.Fab")
		)
		(fp_line
			(start 0.12065 -0.3048)
			(end 0.67945 -0.3048)
			(stroke
				(width 0.1)
				(type default)
			)
			(layer "F.Fab")
		)
		(fp_line
			(start 0.12065 -0.2794)
			(end 0.12065 -0.3048)
			(stroke
				(width 0.1)
				(type default)
			)
			(layer "F.Fab")
		)
		(fp_line
			(start 0.67945 -0.3048)
			(end 0.67945 0.3048)
			(stroke
				(width 0.1)
				(type default)
			)
			(layer "F.Fab")
		)
		(fp_line
			(start 0.67945 0.3048)
			(end 0.120396 0.3048)
			(stroke
				(width 0.1)
				(type default)
			)
			(layer "F.Fab")
		)
		(pad "1" smd circle
			(at -0.40005 0)
			(size 0 0)
			(layers "F.Cu" "F.Mask" "F.Paste")
			(net "SMB_INA230_3V3AUX_SDA_R")
		)
		(pad "2" smd circle
			(at 0.40005 0)
			(size 0 0)
			(layers "F.Cu" "F.Mask" "F.Paste")
			(net "SMB_INA230_3V3AUX_SDA")
		)
	)
)
